# S9S_MB_2U (Grand Teton) — schematic netlist excerpt (pin names and nets, part order shuffled) for the footprints in the layout excerpt that follows; sources: Cadence DE-HDL packaged netlist, KiCad conversion of 03242023_DA0F0TMBIJ0_F0T_Motherboard_J_brd_V01_OCP.brd

PU206  RS31312R  IC  pkg QFN22_TH_3X5  page 163
  EN  = P12V_OCP_V3_2_EN_2_R3
  LOADEN  = GND
  ENTM  = GND
  TIMER  = P12V_OCP_TIMER_2
  ISET  = P12V_OCP_ISET_2
  SS  = P12V_OCP_SS_2
  GND  = GND
  IMON  = P12V_OCP_IMON_2
  FLTB  = P12V_OCP_FLTB_2
  PG  = HP_LVC3_OCP_V3_2_P12V_PWRGD
  OV  = P12V_OCP_OV_FB_2
  AVIN  = P12V_OCP_AVIN_PD_2
  VOUT_13  = P12V_OCP_V3_2
  VOUT_14  = P12V_OCP_V3_2
  VOUT_15  = P12V_OCP_V3_2
  VOUT_16  = P12V_OCP_V3_2
  VOUT_17  = P12V_OCP_V3_2
  VOUT_18  = P12V_OCP_V3_2
  VOUT_19  = P12V_OCP_V3_2
  VOUT_20  = P12V_OCP_V3_2
  VIN_21_22  = P12V_AUX
  VIN_23  = P12V_AUX
  VIN_24  = P12V_AUX
  VIN_25  = P12V_AUX
  VIN_26  = P12V_AUX

(kicad_pcb
	(version 20260206)
	(generator "pcbnew")
	(generator_version "10.0")
	(general
		(thickness 1.6)
		(legacy_teardrops no)
	)
	(paper "A4")
	(title_block
		(title "03242023_DA0F0TMBIJ0_F0T_Motherboard_J_brd_V01_OCP.brd")
		(comment 1 "Grand Teton / footprint 3067 of 6105 (PU206), pads 1-25 of 25")
	)
	(layers
		(0 "F.Cu" signal "TOP")
		(4 "In1.Cu" signal "GND")
		(6 "In2.Cu" signal "IN1")
		(8 "In3.Cu" signal "GND1")
		(10 "In4.Cu" signal "IN2")
		(12 "In5.Cu" signal "GND2")
		(14 "In6.Cu" signal "IN3")
		(16 "In7.Cu" signal "GND3")
		(18 "In8.Cu" signal "VCC")
		(20 "In9.Cu" signal "VCC1")
		(22 "In10.Cu" signal "GND4")
		(24 "In11.Cu" signal "IN4")
		(26 "In12.Cu" signal "GND5")
		(28 "In13.Cu" signal "IN5")
		(30 "In14.Cu" signal "GND6")
		(32 "In15.Cu" signal "IN6")
		(34 "In16.Cu" signal "GND7")
		(2 "B.Cu" signal "BOTTOM")
		(9 "F.Adhes" user "F.Adhesive")
		(11 "B.Adhes" user "B.Adhesive")
		(13 "F.Paste" user "Package Geometry/Pastemask Top")
		(15 "B.Paste" user "Package Geometry/Pastemask Bottom")
		(5 "F.SilkS" user "Ref Des/Silkscreen Top")
		(7 "B.SilkS" user "Ref Des/Silkscreen Bottom")
		(1 "F.Mask" user "Board Geometry/Soldermask Top")
		(3 "B.Mask" user "Board Geometry/Soldermask Bottom")
		(17 "Dwgs.User" user "User.Drawings")
		(19 "Cmts.User" user "User.Comments")
		(21 "Eco1.User" user "User.Eco1")
		(23 "Eco2.User" user "User.Eco2")
		(25 "Edge.Cuts" user "Board Geometry/Outline")
		(27 "Margin" user)
		(31 "F.CrtYd" user "Package Geometry/Place Bound Top")
		(29 "B.CrtYd" user "Package Geometry/Place Bound Bottom")
		(35 "F.Fab" user "Ref Des/Assembly Top")
		(33 "B.Fab" user "Ref Des/Assembly Bottom")
	)
	(footprint ""
		(layer "F.Cu")
		(at 67.672458 -27.889962 -90)
		(property "Reference" "PU206"
			(at -0.065532 -4.389628 0)
			(unlocked yes)
			(layer "F.SilkS")
			(effects
				(font
					(size 0.7874 0.5842)
					(thickness 0.1524)
				)
				(justify left)
			)
		)
		(property "Value" ""
			(at 0 0 270)
			(layer "F.Fab")
			(effects
				(font
					(size 1.27 1.27)
				)
			)
		)
		(duplicate_pad_numbers_are_jumpers no)
		(pad "1" smd circle
			(at -1.374902 -1.999996 180)
			(size 0 0)
			(layers "F.Cu" "F.Mask" "F.Paste")
			(net "P12V_OCP_V3_2_EN_2_R3")
		)
		(pad "2" smd rect
			(at -1.400048 -1.500124 180)
			(size 0.254 0.8128)
			(layers "F.Cu" "F.Mask" "F.Paste")
			(net "GND")
		)
		(pad "3" smd rect
			(at -1.400048 -0.999998 180)
			(size 0.254 0.8128)
			(layers "F.Cu" "F.Mask" "F.Paste")
			(net "GND")
		)
		(pad "4" smd rect
			(at -1.400048 -0.499872 180)
			(size 0.254 0.8128)
			(layers "F.Cu" "F.Mask" "F.Paste")
			(net "P12V_OCP_TIMER_2")
		)
		(pad "5" smd rect
			(at -1.400048 0 180)
			(size 0.254 0.8128)
			(layers "F.Cu" "F.Mask" "F.Paste")
			(net "P12V_OCP_ISET_2")
		)
		(pad "6" smd rect
			(at -1.400048 0.499872 180)
			(size 0.254 0.8128)
			(layers "F.Cu" "F.Mask" "F.Paste")
			(net "P12V_OCP_SS_2")
		)
		(pad "7" smd rect
			(at -1.400048 0.999998 180)
			(size 0.254 0.8128)
			(layers "F.Cu" "F.Mask" "F.Paste")
			(net "GND")
		)
		(pad "8" smd rect
			(at -1.400048 1.500124 180)
			(size 0.254 0.8128)
			(layers "F.Cu" "F.Mask" "F.Paste")
			(net "P12V_OCP_IMON_2")
		)
		(pad "9" smd rect
			(at -1.400048 1.999996 180)
			(size 0.254 0.8128)
			(layers "F.Cu" "F.Mask" "F.Paste")
			(net "P12V_OCP_FLTB_2")
		)
		(pad "10" smd rect
			(at -0.499872 2.400046 270)
			(size 0.254 0.8128)
			(layers "F.Cu" "F.Mask" "F.Paste")
			(net "HP_LVC3_OCP_V3_2_P12V_PWRGD")
		)
		(pad "11" smd rect
			(at 0.499872 2.400046 270)
			(size 0.254 0.8128)
			(layers "F.Cu" "F.Mask" "F.Paste")
			(net "P12V_OCP_OV_FB_2")
		)
		(pad "12" smd rect
			(at 1.400048 1.999996 180)
			(size 0.254 0.8128)
			(layers "F.Cu" "F.Mask" "F.Paste")
			(net "P12V_OCP_AVIN_PD_2")
		)
		(pad "13" smd rect
			(at 1.400048 1.500124 180)
			(size 0.254 0.8128)
			(layers "F.Cu" "F.Mask" "F.Paste")
			(net "P12V_OCP_V3_2")
		)
		(pad "14" smd rect
			(at 1.400048 0.999998 180)
			(size 0.254 0.8128)
			(layers "F.Cu" "F.Mask" "F.Paste")
			(net "P12V_OCP_V3_2")
		)
		(pad "15" smd rect
			(at 1.400048 0.499872 180)
			(size 0.254 0.8128)
			(layers "F.Cu" "F.Mask" "F.Paste")
			(net "P12V_OCP_V3_2")
		)
		(pad "16" smd rect
			(at 1.400048 0 180)
			(size 0.254 0.8128)
			(layers "F.Cu" "F.Mask" "F.Paste")
			(net "P12V_OCP_V3_2")
		)
		(pad "17" smd rect
			(at 1.400048 -0.499872 180)
			(size 0.254 0.8128)
			(layers "F.Cu" "F.Mask" "F.Paste")
			(net "P12V_OCP_V3_2")
		)
		(pad "18" smd rect
			(at 1.400048 -0.999998 180)
			(size 0.254 0.8128)
			(layers "F.Cu" "F.Mask" "F.Paste")
			(net "P12V_OCP_V3_2")
		)
		(pad "19" smd rect
			(at 1.400048 -1.500124 180)
			(size 0.254 0.8128)
			(layers "F.Cu" "F.Mask" "F.Paste")
			(net "P12V_OCP_V3_2")
		)
		(pad "20" smd rect
			(at 1.400048 -1.999996 180)
			(size 0.254 0.8128)
			(layers "F.Cu" "F.Mask" "F.Paste")
			(net "P12V_OCP_V3_2")
		)
		(pad "21_22" smd circle
			(at 0.499872 -2.337562 180)
			(size 0 0)
			(layers "F.Cu" "F.Mask" "F.Paste")
			(net "P12V_AUX")
		)
		(pad "23" smd rect
			(at 0 -1.100074 180)
			(size 0.254 1.27)
			(layers "F.Cu" "F.Mask" "F.Paste")
			(net "P12V_AUX")
		)
		(pad "24" smd rect
			(at 0 -0.199898 180)
			(size 0.254 1.27)
			(layers "F.Cu" "F.Mask" "F.Paste")
			(net "P12V_AUX")
		)
		(pad "25" smd rect
			(at 0 0.700024 180)
			(size 0.254 1.27)
			(layers "F.Cu" "F.Mask" "F.Paste")
			(net "P12V_AUX")
		)
		(pad "26" smd rect
			(at 0 1.599946 180)
			(size 0.254 1.27)
			(layers "F.Cu" "F.Mask" "F.Paste")
			(net "P12V_AUX")
		)
	)
)
